# BASEBOARD_FAB2 (Tioga Pass) — schematic netlist excerpt (pin names and nets, part order shuffled) for the footprints in the layout excerpt that follows; sources: Cadence DE-HDL packaged netlist, KiCad conversion of Wiwynn_Tioga_Pass_MB.brd

L1F2  IND-120NH-30-GP  pkg DISCRET-GB2  page 224 : S = VR_PVDDQ_GHJ_PH2_SW ; F = PVDDQ_GHJ
R8W8  RES  1.00K 1% CHIP  pkg 0402  page 235 : A = P3V3_STBY ; B = PU_PVNN_PCH_PINALRT_N
R7G15  RES  0.0 5% EMPTY  pkg 0402  page 189 : A = JTAG_PCH_PLD_TDO ; B = JTAG_TDO

(kicad_pcb
	(version 20260206)
	(generator "pcbnew")
	(generator_version "10.0")
	(general
		(thickness 1.6)
		(legacy_teardrops no)
	)
	(paper "A4")
	(title_block
		(title "Wiwynn_Tioga_Pass_MB.brd")
		(comment 1 "Tioga Pass / footprints 646-648 of 4770")
	)
	(layers
		(0 "F.Cu" signal "TOP")
		(4 "In1.Cu" signal "L2GND")
		(6 "In2.Cu" signal "L3")
		(8 "In3.Cu" signal "L4GND")
		(10 "In4.Cu" signal "L5")
		(12 "In5.Cu" signal "L6GND")
		(14 "In6.Cu" signal "L7VCC")
		(16 "In7.Cu" signal "L8VCC")
		(18 "In8.Cu" signal "L9GND")
		(20 "In9.Cu" signal "L10")
		(22 "In10.Cu" signal "L11GND")
		(24 "In11.Cu" signal "L12")
		(26 "In12.Cu" signal "L13GND")
		(2 "B.Cu" signal "BOTTOM")
		(9 "F.Adhes" user "F.Adhesive")
		(11 "B.Adhes" user "B.Adhesive")
		(13 "F.Paste" user "Package Geometry/Pastemask Top")
		(15 "B.Paste" user "Package Geometry/Pastemask Bottom")
		(5 "F.SilkS" user "Ref Des/Silkscreen Top")
		(7 "B.SilkS" user "Ref Des/Silkscreen Bottom")
		(1 "F.Mask" user "Board Geometry/Soldermask Top")
		(3 "B.Mask" user "Board Geometry/Soldermask Bottom")
		(17 "Dwgs.User" user "User.Drawings")
		(19 "Cmts.User" user "User.Comments")
		(21 "Eco1.User" user "User.Eco1")
		(23 "Eco2.User" user "User.Eco2")
		(25 "Edge.Cuts" user "Board Geometry/Outline")
		(27 "Margin" user)
		(31 "F.CrtYd" user "Package Geometry/Place Bound Top")
		(29 "B.CrtYd" user "Package Geometry/Place Bound Bottom")
		(35 "F.Fab" user "Ref Des/Assembly Top")
		(33 "B.Fab" user "Ref Des/Assembly Bottom")
	)
	(footprint ""
		(layer "F.Cu")
		(at 10.795 -15.875)
		(property "Reference" "L1F2"
			(at 3.378708 -4.251706 0)
			(unlocked yes)
			(layer "F.SilkS")
			(effects
				(font
					(size 0.4064 0.254)
					(thickness 0.1524)
				)
			)
		)
		(property "Value" ""
			(at 0 0 0)
			(layer "F.Fab")
			(effects
				(font
					(size 1.27 1.27)
				)
			)
		)
		(duplicate_pad_numbers_are_jumpers no)
		(fp_line
			(start -1.1303 -3.199892)
			(end 8.3693 -3.199892)
			(stroke
				(width 0.1524)
				(type default)
			)
			(layer "F.SilkS")
		)
		(fp_line
			(start -1.1303 -1.6637)
			(end -1.1303 -3.199892)
			(stroke
				(width 0.1524)
				(type default)
			)
			(layer "F.SilkS")
		)
		(fp_line
			(start -1.1303 3.199892)
			(end -1.1303 1.6637)
			(stroke
				(width 0.1524)
				(type default)
			)
			(layer "F.SilkS")
		)
		(fp_line
			(start 8.3693 -3.199892)
			(end 8.3693 -1.6637)
			(stroke
				(width 0.1524)
				(type default)
			)
			(layer "F.SilkS")
		)
		(fp_line
			(start 8.3693 1.6637)
			(end 8.3693 3.199892)
			(stroke
				(width 0.1524)
				(type default)
			)
			(layer "F.SilkS")
		)
		(fp_line
			(start 8.3693 3.199892)
			(end -1.1303 3.199892)
			(stroke
				(width 0.1524)
				(type default)
			)
			(layer "F.SilkS")
		)
		(fp_rect
			(start -1.1303 3.199892)
			(end 8.3693 -3.199892)
			(stroke
				(width 0)
				(type default)
			)
			(fill no)
			(layer "F.CrtYd")
		)
		(fp_line
			(start -1.1303 -3.199892)
			(end 8.3693 -3.199892)
			(stroke
				(width 0.1)
				(type default)
			)
			(layer "F.Fab")
		)
		(fp_line
			(start -1.1303 3.199892)
			(end -1.1303 -3.199892)
			(stroke
				(width 0.1)
				(type default)
			)
			(layer "F.Fab")
		)
		(fp_line
			(start 8.3693 -3.199892)
			(end 8.3693 3.199892)
			(stroke
				(width 0.1)
				(type default)
			)
			(layer "F.Fab")
		)
		(fp_line
			(start 8.3693 3.199892)
			(end -1.1303 3.199892)
			(stroke
				(width 0.1)
				(type default)
			)
			(layer "F.Fab")
		)
		(pad "1" smd rect
			(at 0 0)
			(size 3.683 2.667)
			(layers "F.Cu" "F.Mask" "F.Paste")
			(net "VR_PVDDQ_GHJ_PH2_SW")
		)
		(pad "2" smd rect
			(at 7.239 0)
			(size 3.683 2.667)
			(layers "F.Cu" "F.Mask" "F.Paste")
			(net "PVDDQ_GHJ")
		)
	)
	(footprint ""
		(layer "F.Cu")
		(at 384.4798 -0.254)
		(property "Reference" "R7G15"
			(at 0 0 0)
			(layer "F.SilkS")
			(hide yes)
			(effects
				(font
					(size 1.27 1.27)
				)
			)
		)
		(property "Value" ""
			(at 0 0 0)
			(layer "F.Fab")
			(effects
				(font
					(size 1.27 1.27)
				)
			)
		)
		(duplicate_pad_numbers_are_jumpers no)
		(fp_poly
			(pts
				(xy -0.2794 -0.1016) (xy 0.2794 -0.1016) (xy 0.2794 0.9906) (xy -0.2794 0.9906)
			)
			(stroke
				(width 0)
				(type default)
			)
			(fill no)
			(layer "F.CrtYd")
		)
		(fp_line
			(start -0.2794 -0.1016)
			(end -0.2794 0.9906)
			(stroke
				(width 0.1)
				(type default)
			)
			(layer "F.Fab")
		)
		(fp_line
			(start -0.2794 0.9906)
			(end 0.2794 0.9906)
			(stroke
				(width 0.1)
				(type default)
			)
			(layer "F.Fab")
		)
		(fp_line
			(start 0.2794 -0.1016)
			(end -0.2794 -0.1016)
			(stroke
				(width 0.1)
				(type default)
			)
			(layer "F.Fab")
		)
		(fp_line
			(start 0.2794 0.9906)
			(end 0.2794 -0.1016)
			(stroke
				(width 0.1)
				(type default)
			)
			(layer "F.Fab")
		)
		(pad "1" smd rect
			(at 0 0)
			(size 0.508 0.508)
			(layers "F.Cu" "F.Mask" "F.Paste")
			(net "JTAG_PCH_PLD_TDO")
		)
		(pad "2" smd rect
			(at 0 0.889)
			(size 0.508 0.508)
			(layers "F.Cu" "F.Mask" "F.Paste")
			(net "JTAG_TDO")
		)
		(zone
			(layer "F.Cu")
			(hatch none 0.5)
			(connect_pads
				(clearance 0)
			)
			(min_thickness 0.25)
			(keepout
				(tracks allowed)
				(vias not_allowed)
				(pads allowed)
				(copperpour not_allowed)
				(footprints allowed)
			)
			(placement
				(enabled no)
				(sheetname "")
			)
			(fill
				(thermal_gap 0.5)
				(thermal_bridge_width 0.5)
				(island_removal_mode 0)
			)
			(polygon
				(pts
					(xy 384.2258 0) (xy 384.7338 0) (xy 384.7338 0.381) (xy 384.2258 0.381)
				)
			)
		)
		(zone
			(layer "F.Cu")
			(hatch none 0.5)
			(connect_pads
				(clearance 0)
			)
			(min_thickness 0.25)
			(keepout
				(tracks not_allowed)
				(vias allowed)
				(pads allowed)
				(copperpour not_allowed)
				(footprints allowed)
			)
			(placement
				(enabled no)
				(sheetname "")
			)
			(fill
				(thermal_gap 0.5)
				(thermal_bridge_width 0.5)
				(island_removal_mode 0)
			)
			(polygon
				(pts
					(xy 384.2258 0.381) (xy 384.7338 0.381) (xy 384.7338 0) (xy 384.2258 0)
				)
			)
		)
	)
	(footprint ""
		(layer "F.Cu")
		(at 401.13966 -152.66416 -90)
		(property "Reference" "R8W8"
			(at -0.8382 -0.67818 270)
			(unlocked yes)
			(layer "F.SilkS")
			(effects
				(font
					(size 0.4064 0.254)
					(thickness 0.1524)
				)
				(justify left)
			)
		)
		(property "Value" ""
			(at 0 0 270)
			(layer "F.Fab")
			(effects
				(font
					(size 1.27 1.27)
				)
			)
		)
		(duplicate_pad_numbers_are_jumpers no)
		(fp_poly
			(pts
				(xy -0.2794 -0.1016) (xy 0.2794 -0.1016) (xy 0.2794 0.9906) (xy -0.2794 0.9906)
			)
			(stroke
				(width 0)
				(type default)
			)
			(fill no)
			(layer "F.CrtYd")
		)
		(fp_line
			(start -0.2794 0.9906)
			(end 0.2794 0.9906)
			(stroke
				(width 0.1)
				(type default)
			)
			(layer "F.Fab")
		)
		(fp_line
			(start 0.2794 0.9906)
			(end 0.2794 -0.1016)
			(stroke
				(width 0.1)
				(type default)
			)
			(layer "F.Fab")
		)
		(fp_line
			(start -0.2794 -0.1016)
			(end -0.2794 0.9906)
			(stroke
				(width 0.1)
				(type default)
			)
			(layer "F.Fab")
		)
		(fp_line
			(start 0.2794 -0.1016)
			(end -0.2794 -0.1016)
			(stroke
				(width 0.1)
				(type default)
			)
			(layer "F.Fab")
		)
		(pad "1" smd rect
			(at 0 0 270)
			(size 0.508 0.508)
			(layers "F.Cu" "F.Mask" "F.Paste")
			(net "P3V3_STBY")
		)
		(pad "2" smd rect
			(at 0 0.889 270)
			(size 0.508 0.508)
			(layers "F.Cu" "F.Mask" "F.Paste")
			(net "PU_PVNN_PCH_PINALRT_N")
		)
		(zone
			(layer "F.Cu")
			(hatch none 0.5)
			(connect_pads
				(clearance 0)
			)
			(min_thickness 0.25)
			(keepout
				(tracks not_allowed)
				(vias allowed)
				(pads allowed)
				(copperpour not_allowed)
				(footprints allowed)
			)
			(placement
				(enabled no)
				(sheetname "")
			)
			(fill
				(thermal_gap 0.5)
				(thermal_bridge_width 0.5)
				(island_removal_mode 0)
			)
			(polygon
				(pts
					(xy 400.50466 -152.91816) (xy 400.50466 -152.41016) (xy 400.88566 -152.41016) (xy 400.88566 -152.91816)
				)
			)
		)
		(zone
			(layer "F.Cu")
			(hatch none 0.5)
			(connect_pads
				(clearance 0)
			)
			(min_thickness 0.25)
			(keepout
				(tracks allowed)
				(vias not_allowed)
				(pads allowed)
				(copperpour not_allowed)
				(footprints allowed)
			)
			(placement
				(enabled no)
				(sheetname "")
			)
			(fill
				(thermal_gap 0.5)
				(thermal_bridge_width 0.5)
				(island_removal_mode 0)
			)
			(polygon
				(pts
					(xy 400.88566 -152.91816) (xy 400.88566 -152.41016) (xy 400.50466 -152.41016) (xy 400.50466 -152.91816)
				)
			)
		)
	)
)
